(kicad_pcb
	(version 20260206)
	(generator "pcbnew")
	(generator_version "10.0")
	(general
		(thickness 1.6)
		(legacy_teardrops no)
	)
	(paper "A4")
	(title_block
		(title "Bryce Canyon_F.DPB_16315-1-OCP.brd")
		(comment 1 "Bryce Canyon / footprint 1805 of 2223 (MONO4), pads 1-74 of 166")
	)
	(layers
		(0 "F.Cu" signal "TOP")
		(4 "In1.Cu" signal "L2GND")
		(6 "In2.Cu" signal "L3")
		(8 "In3.Cu" signal "L4GND")
		(10 "In4.Cu" signal "L5")
		(12 "In5.Cu" signal "L6VCC")
		(14 "In6.Cu" signal "L7VCC")
		(16 "In7.Cu" signal "L8")
		(18 "In8.Cu" signal "L9GND")
		(20 "In9.Cu" signal "L10")
		(22 "In10.Cu" signal "L11GND")
		(2 "B.Cu" signal "BOTTOM")
		(9 "F.Adhes" user "F.Adhesive")
		(11 "B.Adhes" user "B.Adhesive")
		(13 "F.Paste" user "Package Geometry/Pastemask Top")
		(15 "B.Paste" user "Package Geometry/Pastemask Bottom")
		(5 "F.SilkS" user "Ref Des/Silkscreen Top")
		(7 "B.SilkS" user "Ref Des/Silkscreen Bottom")
		(1 "F.Mask" user "Board Geometry/Soldermask Top")
		(3 "B.Mask" user "Board Geometry/Soldermask Bottom")
		(17 "Dwgs.User" user "User.Drawings")
		(19 "Cmts.User" user "User.Comments")
		(21 "Eco1.User" user "User.Eco1")
		(23 "Eco2.User" user "User.Eco2")
		(25 "Edge.Cuts" user "Board Geometry/Outline")
		(27 "Margin" user)
		(31 "F.CrtYd" user "Package Geometry/Place Bound Top")
		(29 "B.CrtYd" user "Package Geometry/Place Bound Bottom")
		(35 "F.Fab" user "Ref Des/Assembly Top")
		(33 "B.Fab" user "Ref Des/Assembly Bottom")
	)
	(footprint ""
		(layer "F.Cu")
		(at 281.999944 -14.85011 90)
		(property "Reference" "MONO4"
			(at 0 0 90)
			(layer "F.SilkS")
			(hide yes)
			(effects
				(font
					(size 1.27 1.27)
				)
			)
		)
		(property "Value" "AMP-CONN164-4R-1-GP"
			(at -25.705054 -1.203706 90)
			(unlocked yes)
			(layer "F.Fab")
			(hide yes)
			(effects
				(font
					(size 1.016 1.016)
					(thickness 0.1524)
				)
			)
		)
		(property "Device Type" "PREFIT-164P-890091-1H441"
			(at -25.705054 -2.727706 90)
			(unlocked yes)
			(layer "F.Fab")
			(hide yes)
			(effects
				(font
					(size 1.016 1.016)
					(thickness 0.1524)
				)
			)
		)
		(duplicate_pad_numbers_are_jumpers no)
		(pad "" np_thru_hole circle
			(at 0 0 90)
			(size 0.254 0.254)
			(drill 2.3622)
			(layers "*.Cu" "*.Mask")
			(clearance 1.4097)
			(thermal_gap 1.4097)
		)
		(pad "" np_thru_hole circle
			(at 73.149968 0 90)
			(size 0.254 0.254)
			(drill 2.3622)
			(layers "*.Cu" "*.Mask")
			(clearance 1.4097)
			(thermal_gap 1.4097)
		)
		(pad "A1" thru_hole circle
			(at -11.649964 -1.249934 90)
			(size 1.0668 1.0668)
			(drill 0.719836)
			(layers "*.Cu" "*.Mask")
			(remove_unused_layers no)
			(net "COMP_B_SEC_INS_N")
			(clearance 0.1905)
			(thermal_gap 0.1905)
		)
		(pad "A2" thru_hole circle
			(at -10.649966 -3.24993 90)
			(size 1.0668 1.0668)
			(drill 0.719836)
			(layers "*.Cu" "*.Mask")
			(remove_unused_layers no)
			(net "P12V_B_COMP")
			(clearance 0.1905)
			(thermal_gap 0.1905)
		)
		(pad "A3" thru_hole circle
			(at -9.649968 -1.249934 90)
			(size 1.0668 1.0668)
			(drill 0.719836)
			(layers "*.Cu" "*.Mask")
			(remove_unused_layers no)
			(net "P12V_B_COMP")
			(clearance 0.1905)
			(thermal_gap 0.1905)
		)
		(pad "A4" thru_hole circle
			(at -8.64997 -3.24993 90)
			(size 1.0668 1.0668)
			(drill 0.719836)
			(layers "*.Cu" "*.Mask")
			(remove_unused_layers no)
			(net "GND")
			(clearance 0.1905)
			(thermal_gap 0.1905)
		)
		(pad "A5" thru_hole circle
			(at -7.649972 -1.249934 90)
			(size 1.0668 1.0668)
			(drill 0.719836)
			(layers "*.Cu" "*.Mask")
			(remove_unused_layers no)
			(net "TP_COMP_B_NCSI_RCLK")
			(clearance 0.1905)
			(thermal_gap 0.1905)
		)
		(pad "A6" thru_hole circle
			(at -6.649974 -3.24993 90)
			(size 1.0668 1.0668)
			(drill 0.719836)
			(layers "*.Cu" "*.Mask")
			(remove_unused_layers no)
			(net "TP_COMP_B_NCSI_RXD0")
			(clearance 0.1905)
			(thermal_gap 0.1905)
		)
		(pad "A7" thru_hole circle
			(at -5.649976 -1.249934 90)
			(size 1.0668 1.0668)
			(drill 0.719836)
			(layers "*.Cu" "*.Mask")
			(remove_unused_layers no)
			(net "TP_COMP_B_NCSI_RXD1")
			(clearance 0.1905)
			(thermal_gap 0.1905)
		)
		(pad "A8" thru_hole circle
			(at -4.649978 -3.24993 90)
			(size 1.0668 1.0668)
			(drill 0.719836)
			(layers "*.Cu" "*.Mask")
			(remove_unused_layers no)
			(net "GND")
			(clearance 0.1905)
			(thermal_gap 0.1905)
		)
		(pad "A9" thru_hole circle
			(at -3.64998 -1.249934 90)
			(size 1.0668 1.0668)
			(drill 0.719836)
			(layers "*.Cu" "*.Mask")
			(remove_unused_layers no)
			(net "PCIE_COMP_B_TO_IOM_B_CLK_4_DP")
			(clearance 0.1905)
			(thermal_gap 0.1905)
		)
		(pad "A10" thru_hole circle
			(at -2.649982 -3.24993 90)
			(size 1.0668 1.0668)
			(drill 0.719836)
			(layers "*.Cu" "*.Mask")
			(remove_unused_layers no)
			(net "PCIE_COMP_B_TO_IOM_B_CLK_4_DN")
			(clearance 0.1905)
			(thermal_gap 0.1905)
		)
		(pad "A11" thru_hole circle
			(at -1.649984 -1.249934 90)
			(size 1.0668 1.0668)
			(drill 0.719836)
			(layers "*.Cu" "*.Mask")
			(remove_unused_layers no)
			(net "GND")
			(clearance 0.1905)
			(thermal_gap 0.1905)
		)
		(pad "A12" thru_hole circle
			(at 1.35001 -3.24993 90)
			(size 1.0668 1.0668)
			(drill 0.719836)
			(layers "*.Cu" "*.Mask")
			(remove_unused_layers no)
			(net "GND")
			(clearance 0.1905)
			(thermal_gap 0.1905)
		)
		(pad "A13" thru_hole circle
			(at 2.350008 -1.249934 90)
			(size 1.0668 1.0668)
			(drill 0.719836)
			(layers "*.Cu" "*.Mask")
			(remove_unused_layers no)
			(net "PCIE_COMP_B_CLK_P5")
			(clearance 0.1905)
			(thermal_gap 0.1905)
		)
		(pad "A14" thru_hole circle
			(at 3.350006 -3.24993 90)
			(size 1.0668 1.0668)
			(drill 0.719836)
			(layers "*.Cu" "*.Mask")
			(remove_unused_layers no)
			(net "PCIE_COMP_B_CLK_N5")
			(clearance 0.1905)
			(thermal_gap 0.1905)
		)
		(pad "A15" thru_hole circle
			(at 4.350004 -1.249934 90)
			(size 1.0668 1.0668)
			(drill 0.719836)
			(layers "*.Cu" "*.Mask")
			(remove_unused_layers no)
			(net "GND")
			(clearance 0.1905)
			(thermal_gap 0.1905)
		)
		(pad "A16" thru_hole circle
			(at 5.350002 -3.24993 90)
			(size 1.0668 1.0668)
			(drill 0.719836)
			(layers "*.Cu" "*.Mask")
			(remove_unused_layers no)
			(net "GND")
			(clearance 0.1905)
			(thermal_gap 0.1905)
		)
		(pad "A17" thru_hole circle
			(at 6.35 -1.249934 90)
			(size 1.0668 1.0668)
			(drill 0.719836)
			(layers "*.Cu" "*.Mask")
			(remove_unused_layers no)
			(net "Net_1379")
			(clearance 0.1905)
			(thermal_gap 0.1905)
		)
		(pad "A18" thru_hole circle
			(at 7.349998 -3.24993 90)
			(size 1.0668 1.0668)
			(drill 0.719836)
			(layers "*.Cu" "*.Mask")
			(remove_unused_layers no)
			(net "Net_1376")
			(clearance 0.1905)
			(thermal_gap 0.1905)
		)
		(pad "A19" thru_hole circle
			(at 8.349996 -1.249934 90)
			(size 1.0668 1.0668)
			(drill 0.719836)
			(layers "*.Cu" "*.Mask")
			(remove_unused_layers no)
			(net "GND")
			(clearance 0.1905)
			(thermal_gap 0.1905)
		)
		(pad "A20" thru_hole circle
			(at 9.349994 -3.24993 90)
			(size 1.0668 1.0668)
			(drill 0.719836)
			(layers "*.Cu" "*.Mask")
			(remove_unused_layers no)
			(net "GND")
			(clearance 0.1905)
			(thermal_gap 0.1905)
		)
		(pad "A21" thru_hole circle
			(at 10.349992 -1.249934 90)
			(size 1.0668 1.0668)
			(drill 0.719836)
			(layers "*.Cu" "*.Mask")
			(remove_unused_layers no)
			(net "Net_1378")
			(clearance 0.1905)
			(thermal_gap 0.1905)
		)
		(pad "A22" thru_hole circle
			(at 11.34999 -3.24993 90)
			(size 1.0668 1.0668)
			(drill 0.719836)
			(layers "*.Cu" "*.Mask")
			(remove_unused_layers no)
			(net "Net_1371")
			(clearance 0.1905)
			(thermal_gap 0.1905)
		)
		(pad "A23" thru_hole circle
			(at 12.349988 -1.249934 90)
			(size 1.0668 1.0668)
			(drill 0.719836)
			(layers "*.Cu" "*.Mask")
			(remove_unused_layers no)
			(net "GND")
			(clearance 0.1905)
			(thermal_gap 0.1905)
		)
		(pad "A24" thru_hole circle
			(at 13.349986 -3.24993 90)
			(size 1.0668 1.0668)
			(drill 0.719836)
			(layers "*.Cu" "*.Mask")
			(remove_unused_layers no)
			(net "GND")
			(clearance 0.1905)
			(thermal_gap 0.1905)
		)
		(pad "A25" thru_hole circle
			(at 14.349984 -1.249934 90)
			(size 1.0668 1.0668)
			(drill 0.719836)
			(layers "*.Cu" "*.Mask")
			(remove_unused_layers no)
			(net "Net_1374")
			(clearance 0.1905)
			(thermal_gap 0.1905)
		)
		(pad "A26" thru_hole circle
			(at 15.349982 -3.24993 90)
			(size 1.0668 1.0668)
			(drill 0.719836)
			(layers "*.Cu" "*.Mask")
			(remove_unused_layers no)
			(net "Net_1370")
			(clearance 0.1905)
			(thermal_gap 0.1905)
		)
		(pad "A27" thru_hole circle
			(at 16.34998 -1.249934 90)
			(size 1.0668 1.0668)
			(drill 0.719836)
			(layers "*.Cu" "*.Mask")
			(remove_unused_layers no)
			(net "GND")
			(clearance 0.1905)
			(thermal_gap 0.1905)
		)
		(pad "A28" thru_hole circle
			(at 17.349978 -3.24993 90)
			(size 1.0668 1.0668)
			(drill 0.719836)
			(layers "*.Cu" "*.Mask")
			(remove_unused_layers no)
			(net "GND")
			(clearance 0.1905)
			(thermal_gap 0.1905)
		)
		(pad "A29" thru_hole circle
			(at 18.349976 -1.249934 90)
			(size 1.0668 1.0668)
			(drill 0.719836)
			(layers "*.Cu" "*.Mask")
			(remove_unused_layers no)
			(net "Net_1368")
			(clearance 0.1905)
			(thermal_gap 0.1905)
		)
		(pad "A30" thru_hole circle
			(at 19.349974 -3.24993 90)
			(size 1.0668 1.0668)
			(drill 0.719836)
			(layers "*.Cu" "*.Mask")
			(remove_unused_layers no)
			(net "Net_1367")
			(clearance 0.1905)
			(thermal_gap 0.1905)
		)
		(pad "A31" thru_hole circle
			(at 20.349972 -1.249934 90)
			(size 1.0668 1.0668)
			(drill 0.719836)
			(layers "*.Cu" "*.Mask")
			(remove_unused_layers no)
			(net "GND")
			(clearance 0.1905)
			(thermal_gap 0.1905)
		)
		(pad "A32" thru_hole circle
			(at 21.34997 -3.24993 90)
			(size 1.0668 1.0668)
			(drill 0.719836)
			(layers "*.Cu" "*.Mask")
			(remove_unused_layers no)
			(net "GND")
			(clearance 0.1905)
			(thermal_gap 0.1905)
		)
		(pad "A33" thru_hole circle
			(at 22.349968 -1.249934 90)
			(size 1.0668 1.0668)
			(drill 0.719836)
			(layers "*.Cu" "*.Mask")
			(remove_unused_layers no)
			(net "PCIE_IOM_B_TO_COMP_B_12_DP")
			(clearance 0.1905)
			(thermal_gap 0.1905)
		)
		(pad "A34" thru_hole circle
			(at 23.349966 -3.24993 90)
			(size 1.0668 1.0668)
			(drill 0.719836)
			(layers "*.Cu" "*.Mask")
			(remove_unused_layers no)
			(net "PCIE_IOM_B_TO_COMP_B_12_DN")
			(clearance 0.1905)
			(thermal_gap 0.1905)
		)
		(pad "A35" thru_hole circle
			(at 24.349964 -1.249934 90)
			(size 1.0668 1.0668)
			(drill 0.719836)
			(layers "*.Cu" "*.Mask")
			(remove_unused_layers no)
			(net "GND")
			(clearance 0.1905)
			(thermal_gap 0.1905)
		)
		(pad "A36" thru_hole circle
			(at 25.349962 -3.24993 90)
			(size 1.0668 1.0668)
			(drill 0.719836)
			(layers "*.Cu" "*.Mask")
			(remove_unused_layers no)
			(net "GND")
			(clearance 0.1905)
			(thermal_gap 0.1905)
		)
		(pad "A37" thru_hole circle
			(at 26.34996 -1.249934 90)
			(size 1.0668 1.0668)
			(drill 0.719836)
			(layers "*.Cu" "*.Mask")
			(remove_unused_layers no)
			(net "PCIE_IOM_B_TO_COMP_B_13_DP")
			(clearance 0.1905)
			(thermal_gap 0.1905)
		)
		(pad "A38" thru_hole circle
			(at 27.349958 -3.24993 90)
			(size 1.0668 1.0668)
			(drill 0.719836)
			(layers "*.Cu" "*.Mask")
			(remove_unused_layers no)
			(net "PCIE_IOM_B_TO_COMP_B_13_DN")
			(clearance 0.1905)
			(thermal_gap 0.1905)
		)
		(pad "A39" thru_hole circle
			(at 28.349956 -1.249934 90)
			(size 1.0668 1.0668)
			(drill 0.719836)
			(layers "*.Cu" "*.Mask")
			(remove_unused_layers no)
			(net "GND")
			(clearance 0.1905)
			(thermal_gap 0.1905)
		)
		(pad "A40" thru_hole circle
			(at 29.349954 -3.24993 90)
			(size 1.0668 1.0668)
			(drill 0.719836)
			(layers "*.Cu" "*.Mask")
			(remove_unused_layers no)
			(net "GND")
			(clearance 0.1905)
			(thermal_gap 0.1905)
		)
		(pad "A41" thru_hole circle
			(at 30.349952 -1.249934 90)
			(size 1.0668 1.0668)
			(drill 0.719836)
			(layers "*.Cu" "*.Mask")
			(remove_unused_layers no)
			(net "PCIE_IOM_B_TO_COMP_B_14_DP")
			(clearance 0.1905)
			(thermal_gap 0.1905)
		)
		(pad "A42" thru_hole circle
			(at 31.34995 -3.24993 90)
			(size 1.0668 1.0668)
			(drill 0.719836)
			(layers "*.Cu" "*.Mask")
			(remove_unused_layers no)
			(net "PCIE_IOM_B_TO_COMP_B_14_DN")
			(clearance 0.1905)
			(thermal_gap 0.1905)
		)
		(pad "A43" thru_hole circle
			(at 32.349948 -1.249934 90)
			(size 1.0668 1.0668)
			(drill 0.719836)
			(layers "*.Cu" "*.Mask")
			(remove_unused_layers no)
			(net "GND")
			(clearance 0.1905)
			(thermal_gap 0.1905)
		)
		(pad "A44" thru_hole circle
			(at 33.349946 -3.24993 90)
			(size 1.0668 1.0668)
			(drill 0.719836)
			(layers "*.Cu" "*.Mask")
			(remove_unused_layers no)
			(net "GND")
			(clearance 0.1905)
			(thermal_gap 0.1905)
		)
		(pad "A45" thru_hole circle
			(at 34.349944 -1.249934 90)
			(size 1.0668 1.0668)
			(drill 0.719836)
			(layers "*.Cu" "*.Mask")
			(remove_unused_layers no)
			(net "PCIE_IOM_B_TO_COMP_B_15_DP")
			(clearance 0.1905)
			(thermal_gap 0.1905)
		)
		(pad "A46" thru_hole circle
			(at 35.349942 -3.24993 90)
			(size 1.0668 1.0668)
			(drill 0.719836)
			(layers "*.Cu" "*.Mask")
			(remove_unused_layers no)
			(net "PCIE_IOM_B_TO_COMP_B_15_DN")
			(clearance 0.1905)
			(thermal_gap 0.1905)
		)
		(pad "A47" thru_hole circle
			(at 36.34994 -1.249934 90)
			(size 1.0668 1.0668)
			(drill 0.719836)
			(layers "*.Cu" "*.Mask")
			(remove_unused_layers no)
			(net "GND")
			(clearance 0.1905)
			(thermal_gap 0.1905)
		)
		(pad "A48" thru_hole circle
			(at 37.349938 -3.24993 90)
			(size 1.0668 1.0668)
			(drill 0.719836)
			(layers "*.Cu" "*.Mask")
			(remove_unused_layers no)
			(net "GND")
			(clearance 0.1905)
			(thermal_gap 0.1905)
		)
		(pad "A49" thru_hole circle
			(at 38.349936 -1.249934 90)
			(size 1.0668 1.0668)
			(drill 0.719836)
			(layers "*.Cu" "*.Mask")
			(remove_unused_layers no)
			(net "PCIE_IOM_B_TO_COMP_B_16_DP")
			(clearance 0.1905)
			(thermal_gap 0.1905)
		)
		(pad "A50" thru_hole circle
			(at 39.349934 -3.24993 90)
			(size 1.0668 1.0668)
			(drill 0.719836)
			(layers "*.Cu" "*.Mask")
			(remove_unused_layers no)
			(net "PCIE_IOM_B_TO_COMP_B_16_DN")
			(clearance 0.1905)
			(thermal_gap 0.1905)
		)
		(pad "A51" thru_hole circle
			(at 40.349932 -1.249934 90)
			(size 1.0668 1.0668)
			(drill 0.719836)
			(layers "*.Cu" "*.Mask")
			(remove_unused_layers no)
			(net "GND")
			(clearance 0.1905)
			(thermal_gap 0.1905)
		)
		(pad "A52" thru_hole circle
			(at 41.34993 -3.24993 90)
			(size 1.0668 1.0668)
			(drill 0.719836)
			(layers "*.Cu" "*.Mask")
			(remove_unused_layers no)
			(net "GND")
			(clearance 0.1905)
			(thermal_gap 0.1905)
		)
		(pad "A53" thru_hole circle
			(at 42.349928 -1.249934 90)
			(size 1.0668 1.0668)
			(drill 0.719836)
			(layers "*.Cu" "*.Mask")
			(remove_unused_layers no)
			(net "PCIE_IOM_B_TO_COMP_B_17_DP")
			(clearance 0.1905)
			(thermal_gap 0.1905)
		)
		(pad "A54" thru_hole circle
			(at 43.349926 -3.24993 90)
			(size 1.0668 1.0668)
			(drill 0.719836)
			(layers "*.Cu" "*.Mask")
			(remove_unused_layers no)
			(net "PCIE_IOM_B_TO_COMP_B_17_DN")
			(clearance 0.1905)
			(thermal_gap 0.1905)
		)
		(pad "A55" thru_hole circle
			(at 44.349924 -1.249934 90)
			(size 1.0668 1.0668)
			(drill 0.719836)
			(layers "*.Cu" "*.Mask")
			(remove_unused_layers no)
			(net "GND")
			(clearance 0.1905)
			(thermal_gap 0.1905)
		)
		(pad "A56" thru_hole circle
			(at 45.349922 -3.24993 90)
			(size 1.0668 1.0668)
			(drill 0.719836)
			(layers "*.Cu" "*.Mask")
			(remove_unused_layers no)
			(net "GND")
			(clearance 0.1905)
			(thermal_gap 0.1905)
		)
		(pad "A57" thru_hole circle
			(at 46.34992 -1.249934 90)
			(size 1.0668 1.0668)
			(drill 0.719836)
			(layers "*.Cu" "*.Mask")
			(remove_unused_layers no)
			(net "PCIE_IOM_B_TO_COMP_B_18_DP")
			(clearance 0.1905)
			(thermal_gap 0.1905)
		)
		(pad "A58" thru_hole circle
			(at 47.349918 -3.24993 90)
			(size 1.0668 1.0668)
			(drill 0.719836)
			(layers "*.Cu" "*.Mask")
			(remove_unused_layers no)
			(net "PCIE_IOM_B_TO_COMP_B_18_DN")
			(clearance 0.1905)
			(thermal_gap 0.1905)
		)
		(pad "A59" thru_hole circle
			(at 48.349916 -1.249934 90)
			(size 1.0668 1.0668)
			(drill 0.719836)
			(layers "*.Cu" "*.Mask")
			(remove_unused_layers no)
			(net "GND")
			(clearance 0.1905)
			(thermal_gap 0.1905)
		)
		(pad "A60" thru_hole circle
			(at 49.349914 -3.24993 90)
			(size 1.0668 1.0668)
			(drill 0.719836)
			(layers "*.Cu" "*.Mask")
			(remove_unused_layers no)
			(net "GND")
			(clearance 0.1905)
			(thermal_gap 0.1905)
		)
		(pad "A61" thru_hole circle
			(at 50.349912 -1.249934 90)
			(size 1.0668 1.0668)
			(drill 0.719836)
			(layers "*.Cu" "*.Mask")
			(remove_unused_layers no)
			(net "PCIE_IOM_B_TO_COMP_B_19_DP")
			(clearance 0.1905)
			(thermal_gap 0.1905)
		)
		(pad "A62" thru_hole circle
			(at 51.34991 -3.24993 90)
			(size 1.0668 1.0668)
			(drill 0.719836)
			(layers "*.Cu" "*.Mask")
			(remove_unused_layers no)
			(net "PCIE_IOM_B_TO_COMP_B_19_DN")
			(clearance 0.1905)
			(thermal_gap 0.1905)
		)
		(pad "A63" thru_hole circle
			(at 52.349908 -1.249934 90)
			(size 1.0668 1.0668)
			(drill 0.719836)
			(layers "*.Cu" "*.Mask")
			(remove_unused_layers no)
			(net "GND")
			(clearance 0.1905)
			(thermal_gap 0.1905)
		)
		(pad "A64" thru_hole circle
			(at 53.349906 -3.24993 90)
			(size 1.0668 1.0668)
			(drill 0.719836)
			(layers "*.Cu" "*.Mask")
			(remove_unused_layers no)
			(net "GND")
			(clearance 0.1905)
			(thermal_gap 0.1905)
		)
		(pad "A65" thru_hole circle
			(at 54.349904 -1.249934 90)
			(size 1.0668 1.0668)
			(drill 0.719836)
			(layers "*.Cu" "*.Mask")
			(remove_unused_layers no)
			(net "PCIE_IOM_B_TO_COMP_B_20_DP")
			(clearance 0.1905)
			(thermal_gap 0.1905)
		)
		(pad "A66" thru_hole circle
			(at 55.349902 -3.24993 90)
			(size 1.0668 1.0668)
			(drill 0.719836)
			(layers "*.Cu" "*.Mask")
			(remove_unused_layers no)
			(net "PCIE_IOM_B_TO_COMP_B_20_DN")
			(clearance 0.1905)
			(thermal_gap 0.1905)
		)
		(pad "A67" thru_hole circle
			(at 56.3499 -1.249934 90)
			(size 1.0668 1.0668)
			(drill 0.719836)
			(layers "*.Cu" "*.Mask")
			(remove_unused_layers no)
			(net "GND")
			(clearance 0.1905)
			(thermal_gap 0.1905)
		)
		(pad "A68" thru_hole circle
			(at 57.349898 -3.24993 90)
			(size 1.0668 1.0668)
			(drill 0.719836)
			(layers "*.Cu" "*.Mask")
			(remove_unused_layers no)
			(net "GND")
			(clearance 0.1905)
			(thermal_gap 0.1905)
		)
		(pad "A69" thru_hole circle
			(at 58.349896 -1.249934 90)
			(size 1.0668 1.0668)
			(drill 0.719836)
			(layers "*.Cu" "*.Mask")
			(remove_unused_layers no)
			(net "PCIE_IOM_B_TO_COMP_B_21_DP")
			(clearance 0.1905)
			(thermal_gap 0.1905)
		)
		(pad "A70" thru_hole circle
			(at 59.349894 -3.24993 90)
			(size 1.0668 1.0668)
			(drill 0.719836)
			(layers "*.Cu" "*.Mask")
			(remove_unused_layers no)
			(net "PCIE_IOM_B_TO_COMP_B_21_DN")
			(clearance 0.1905)
			(thermal_gap 0.1905)
		)
		(pad "A71" thru_hole circle
			(at 60.349892 -1.249934 90)
			(size 1.0668 1.0668)
			(drill 0.719836)
			(layers "*.Cu" "*.Mask")
			(remove_unused_layers no)
			(net "GND")
			(clearance 0.1905)
			(thermal_gap 0.1905)
		)
		(pad "A72" thru_hole circle
			(at 61.34989 -3.24993 90)
			(size 1.0668 1.0668)
			(drill 0.719836)
			(layers "*.Cu" "*.Mask")
			(remove_unused_layers no)
			(net "GND")
			(clearance 0.1905)
			(thermal_gap 0.1905)
		)
	)
)
